# T6G (Grand Teton) — schematic netlist excerpt (pin names and nets, part order shuffled) for the footprints in the layout excerpt that follows; sources: Cadence DE-HDL packaged netlist, KiCad conversion of 04192023_DAF0TMB3IC0_F0TG_MB_C_brd_V02_OCP.brd

C2133  Q_CAP  22UF 4V 20% X6S  pkg C0402  page 68 : A = PVDD11_S3_P0 ; B = GND
C2564  Q_CAP  22UF 4V 20% X6S  pkg C0402  page 70 : A = PVDDCR_SOC_P0 ; B = GND

(kicad_pcb
	(version 20260206)
	(generator "pcbnew")
	(generator_version "10.0")
	(general
		(thickness 1.6)
		(legacy_teardrops no)
	)
	(paper "A4")
	(title_block
		(title "04192023_DAF0TMB3IC0_F0TG_MB_C_brd_V02_OCP.brd")
		(comment 1 "Grand Teton / footprints 454-455 of 8354")
	)
	(layers
		(0 "F.Cu" signal "TOP")
		(4 "In1.Cu" signal "GND")
		(6 "In2.Cu" signal "IN1")
		(8 "In3.Cu" signal "GND1")
		(10 "In4.Cu" signal "IN2")
		(12 "In5.Cu" signal "GND2")
		(14 "In6.Cu" signal "IN3")
		(16 "In7.Cu" signal "GND3")
		(18 "In8.Cu" signal "VCC")
		(20 "In9.Cu" signal "VCC1")
		(22 "In10.Cu" signal "GND4")
		(24 "In11.Cu" signal "IN4")
		(26 "In12.Cu" signal "GND5")
		(28 "In13.Cu" signal "IN5")
		(30 "In14.Cu" signal "GND6")
		(32 "In15.Cu" signal "IN6")
		(34 "In16.Cu" signal "GND7")
		(2 "B.Cu" signal "BOTTOM")
		(9 "F.Adhes" user "F.Adhesive")
		(11 "B.Adhes" user "B.Adhesive")
		(13 "F.Paste" user "Package Geometry/Pastemask Top")
		(15 "B.Paste" user "Package Geometry/Pastemask Bottom")
		(5 "F.SilkS" user "Ref Des/Silkscreen Top")
		(7 "B.SilkS" user "Ref Des/Silkscreen Bottom")
		(1 "F.Mask" user "Board Geometry/Soldermask Top")
		(3 "B.Mask" user "Board Geometry/Soldermask Bottom")
		(17 "Dwgs.User" user "User.Drawings")
		(19 "Cmts.User" user "User.Comments")
		(21 "Eco1.User" user "User.Eco1")
		(23 "Eco2.User" user "User.Eco2")
		(25 "Edge.Cuts" user "Board Geometry/Outline")
		(27 "Margin" user)
		(31 "F.CrtYd" user "Package Geometry/Place Bound Top")
		(29 "B.CrtYd" user "Package Geometry/Place Bound Bottom")
		(35 "F.Fab" user "Ref Des/Assembly Top")
		(33 "B.Fab" user "Ref Des/Assembly Bottom")
	)
	(footprint ""
		(layer "F.Cu")
		(at 365.835692 -262.204962 180)
		(property "Reference" "C2133"
			(at 0 0 180)
			(layer "F.SilkS")
			(hide yes)
			(effects
				(font
					(size 1.27 1.27)
				)
			)
		)
		(property "Value" ""
			(at 0 0 180)
			(layer "F.Fab")
			(effects
				(font
					(size 1.27 1.27)
				)
			)
		)
		(duplicate_pad_numbers_are_jumpers no)
		(fp_line
			(start 0.7874 0.4064)
			(end -0.7874 0.4064)
			(stroke
				(width 0.1524)
				(type default)
			)
			(layer "F.SilkS")
		)
		(fp_line
			(start 0.7874 -0.4064)
			(end 0.7874 0.4064)
			(stroke
				(width 0.1524)
				(type default)
			)
			(layer "F.SilkS")
		)
		(fp_line
			(start -0.7874 0.4064)
			(end -0.7874 -0.4064)
			(stroke
				(width 0.1524)
				(type default)
			)
			(layer "F.SilkS")
		)
		(fp_line
			(start -0.7874 -0.4064)
			(end 0.7874 -0.4064)
			(stroke
				(width 0.1524)
				(type default)
			)
			(layer "F.SilkS")
		)
		(fp_line
			(start 0.67945 0.3048)
			(end 0.120396 0.3048)
			(stroke
				(width 0.1)
				(type default)
			)
			(layer "F.Fab")
		)
		(fp_line
			(start 0.67945 -0.3048)
			(end 0.67945 0.3048)
			(stroke
				(width 0.1)
				(type default)
			)
			(layer "F.Fab")
		)
		(fp_line
			(start 0.12065 -0.2794)
			(end 0.12065 -0.3048)
			(stroke
				(width 0.1)
				(type default)
			)
			(layer "F.Fab")
		)
		(fp_line
			(start 0.12065 -0.3048)
			(end 0.67945 -0.3048)
			(stroke
				(width 0.1)
				(type default)
			)
			(layer "F.Fab")
		)
		(fp_line
			(start 0.120396 0.3048)
			(end 0.120396 0.2794)
			(stroke
				(width 0.1)
				(type default)
			)
			(layer "F.Fab")
		)
		(fp_line
			(start 0.120396 0.2794)
			(end -0.12065 0.2794)
			(stroke
				(width 0.1)
				(type default)
			)
			(layer "F.Fab")
		)
		(fp_line
			(start -0.12065 0.3048)
			(end -0.67945 0.3048)
			(stroke
				(width 0.1)
				(type default)
			)
			(layer "F.Fab")
		)
		(fp_line
			(start -0.12065 0.2794)
			(end -0.12065 0.3048)
			(stroke
				(width 0.1)
				(type default)
			)
			(layer "F.Fab")
		)
		(fp_line
			(start -0.12065 -0.2794)
			(end 0.12065 -0.2794)
			(stroke
				(width 0.1)
				(type default)
			)
			(layer "F.Fab")
		)
		(fp_line
			(start -0.12065 -0.305054)
			(end -0.12065 -0.2794)
			(stroke
				(width 0.1)
				(type default)
			)
			(layer "F.Fab")
		)
		(fp_line
			(start -0.67945 0.3048)
			(end -0.67945 -0.305054)
			(stroke
				(width 0.1)
				(type default)
			)
			(layer "F.Fab")
		)
		(fp_line
			(start -0.67945 -0.305054)
			(end -0.12065 -0.305054)
			(stroke
				(width 0.1)
				(type default)
			)
			(layer "F.Fab")
		)
		(pad "1" smd circle
			(at -0.40005 0 180)
			(size 0 0)
			(layers "F.Cu" "F.Mask" "F.Paste")
			(net "PVDD11_S3_P0")
		)
		(pad "2" smd circle
			(at 0.40005 0 180)
			(size 0 0)
			(layers "F.Cu" "F.Mask" "F.Paste")
			(net "GND")
		)
	)
	(footprint ""
		(layer "F.Cu")
		(at 363.645958 -257.744976)
		(property "Reference" "C2564"
			(at 0 0 0)
			(layer "F.SilkS")
			(hide yes)
			(effects
				(font
					(size 1.27 1.27)
				)
			)
		)
		(property "Value" ""
			(at 0 0 0)
			(layer "F.Fab")
			(effects
				(font
					(size 1.27 1.27)
				)
			)
		)
		(duplicate_pad_numbers_are_jumpers no)
		(fp_line
			(start -0.7874 -0.4064)
			(end 0.7874 -0.4064)
			(stroke
				(width 0.1524)
				(type default)
			)
			(layer "F.SilkS")
		)
		(fp_line
			(start -0.7874 0.4064)
			(end -0.7874 -0.4064)
			(stroke
				(width 0.1524)
				(type default)
			)
			(layer "F.SilkS")
		)
		(fp_line
			(start 0.7874 -0.4064)
			(end 0.7874 0.4064)
			(stroke
				(width 0.1524)
				(type default)
			)
			(layer "F.SilkS")
		)
		(fp_line
			(start 0.7874 0.4064)
			(end -0.7874 0.4064)
			(stroke
				(width 0.1524)
				(type default)
			)
			(layer "F.SilkS")
		)
		(fp_line
			(start -0.67945 -0.305054)
			(end -0.12065 -0.305054)
			(stroke
				(width 0.1)
				(type default)
			)
			(layer "F.Fab")
		)
		(fp_line
			(start -0.67945 0.3048)
			(end -0.67945 -0.305054)
			(stroke
				(width 0.1)
				(type default)
			)
			(layer "F.Fab")
		)
		(fp_line
			(start -0.12065 -0.305054)
			(end -0.12065 -0.2794)
			(stroke
				(width 0.1)
				(type default)
			)
			(layer "F.Fab")
		)
		(fp_line
			(start -0.12065 -0.2794)
			(end 0.12065 -0.2794)
			(stroke
				(width 0.1)
				(type default)
			)
			(layer "F.Fab")
		)
		(fp_line
			(start -0.12065 0.2794)
			(end -0.12065 0.3048)
			(stroke
				(width 0.1)
				(type default)
			)
			(layer "F.Fab")
		)
		(fp_line
			(start -0.12065 0.3048)
			(end -0.67945 0.3048)
			(stroke
				(width 0.1)
				(type default)
			)
			(layer "F.Fab")
		)
		(fp_line
			(start 0.120396 0.2794)
			(end -0.12065 0.2794)
			(stroke
				(width 0.1)
				(type default)
			)
			(layer "F.Fab")
		)
		(fp_line
			(start 0.120396 0.3048)
			(end 0.120396 0.2794)
			(stroke
				(width 0.1)
				(type default)
			)
			(layer "F.Fab")
		)
		(fp_line
			(start 0.12065 -0.3048)
			(end 0.67945 -0.3048)
			(stroke
				(width 0.1)
				(type default)
			)
			(layer "F.Fab")
		)
		(fp_line
			(start 0.12065 -0.2794)
			(end 0.12065 -0.3048)
			(stroke
				(width 0.1)
				(type default)
			)
			(layer "F.Fab")
		)
		(fp_line
			(start 0.67945 -0.3048)
			(end 0.67945 0.3048)
			(stroke
				(width 0.1)
				(type default)
			)
			(layer "F.Fab")
		)
		(fp_line
			(start 0.67945 0.3048)
			(end 0.120396 0.3048)
			(stroke
				(width 0.1)
				(type default)
			)
			(layer "F.Fab")
		)
		(pad "1" smd circle
			(at -0.40005 0)
			(size 0 0)
			(layers "F.Cu" "F.Mask" "F.Paste")
			(net "PVDDCR_SOC_P0")
		)
		(pad "2" smd circle
			(at 0.40005 0)
			(size 0 0)
			(layers "F.Cu" "F.Mask" "F.Paste")
			(net "GND")
		)
	)
)
